FILE_TYPE = CONNECTIVITY;
{Allegro Design Entry HDL 16.6-p007 (v16-6-112F) 10/10/2012}
"PAGE_NUMBER" = 50;
0"NC";
1"M_D_DQ<63:0>";
2"M_D_ECC<7:0>";
3"M_D_CKE<3:0>";
4"M_D_ODT<3:0>";
5"M_D_CLK_DN<3:0>";
6"M_D_CLK_DP<3:0>";
7"M_D_CS_N<7:0>";
8"M_D_BA<1:0>";
9"M_D_MA<17:0>";
10"M_D_BG<1:0>";
11"M_D_DQS_DP<17:0>";
12"M_D_DQS_DN<17:0>";
13"GND\g";
14"PVPP_DEF\g";
15"GND\g";
16"GND\g";
17"P12V_NVDIMM_DEF\g";
18"GND\g";
19"PVPP_DEF\g";
20"PVTT_DEF\g";
21"PVDDQ_DEF\g";
22"M_D_DQ<17>";
23"M_D_DQ<18>";
24"M_D_DQS_DP<0>";
25"M_D_DQS_DN<5>";
26"M_D_DQS_DP<4>";
27"M_D_DQ<58>";
28"M_D_DQ<59>";
29"M_D_DQS_DN<14>";
30"M_D_DQS_DN<13>";
31"M_D_DQ<53>";
32"M_D_DQ<49>";
33"TP_CH_D_DIMM_D1_RFU_1";
34"M_D_DQ<0>";
35"M_D_MA<14>";
36"FM_ADR_COMPLETE_DEF_N";
37"M_D_VREF";
38"M_D_DQ<39>";
39"M_D_DQS_DN<8>";
40"M_D_DQS_DN<1>";
41"M_D_DQS_DN<2>";
42"M_D_DQS_DP<2>";
43"M_D_DQ<57>";
44"M_D_DQ<52>";
45"M_D_DQS_DN<11>";
46"M_D_DQS_DN<9>";
47"M_D_DQS_DN<7>";
48"M_D_DQS_DN<6>";
49"M_D_DQS_DN<4>";
50"M_D_DQS_DN<3>";
51"M_D_DQS_DN<17>";
52"M_D_DQS_DN<16>";
53"M_D_DQS_DN<15>";
54"M_D_DQS_DN<12>";
55"M_D_DQS_DN<10>";
56"M_D_DQS_DN<0>";
57"M_D_DQS_DP<17>";
58"M_D_DQS_DP<16>";
59"M_D_DQS_DP<15>";
60"M_D_DQS_DP<14>";
61"M_D_DQS_DP<13>";
62"M_D_DQS_DP<12>";
63"M_D_DQS_DP<11>";
64"M_D_DQS_DP<10>";
65"M_D_DQ<50>";
66"M_D_DQ<51>";
67"M_D_DQ<54>";
68"M_D_DQ<55>";
69"M_D_DQ<56>";
70"M_D_DQ<60>";
71"M_D_DQ<61>";
72"M_D_DQ<62>";
73"M_D_DQ<63>";
74"M_D_MA<16>";
75"M_D_MA<15>";
76"M_D_MA<17>";
77"M_D_MA<11>";
78"M_D_MA<10>";
79"M_D_MA<9>";
80"M_D_MA<8>";
81"M_D_MA<7>";
82"M_D_MA<6>";
83"M_D_MA<5>";
84"M_D_MA<4>";
85"M_D_MA<13>";
86"M_D_MA<12>";
87"M_D_DQS_DP<9>";
88"M_D_DQS_DP<8>";
89"M_D_DQS_DP<7>";
90"M_D_DQS_DP<6>";
91"M_D_DQS_DP<5>";
92"M_D_DQS_DP<3>";
93"M_D_DQS_DP<1>";
94"M_D_DQ<47>";
95"M_D_DQ<48>";
96"M_D_DQ<38>";
97"M_D_DQ<36>";
98"M_D_DQ<35>";
99"M_D_DQ<30>";
100"M_D_DQ<31>";
101"M_D_DQ<32>";
102"M_D_DQ<33>";
103"M_D_DQ<34>";
104"M_D_DQ<37>";
105"M_D_DQ<40>";
106"M_D_DQ<41>";
107"M_D_DQ<42>";
108"M_D_DQ<43>";
109"M_D_DQ<44>";
110"M_D_DQ<45>";
111"M_D_DQ<46>";
112"M_D_DQ<15>";
113"M_D_DQ<26>";
114"M_D_DQ<27>";
115"M_D_DQ<9>";
116"M_D_DQ<10>";
117"M_D_DQ<11>";
118"M_D_DQ<12>";
119"M_D_DQ<13>";
120"M_D_DQ<14>";
121"M_D_DQ<16>";
122"M_D_DQ<19>";
123"M_D_DQ<20>";
124"M_D_DQ<21>";
125"M_D_DQ<22>";
126"M_D_DQ<23>";
127"M_D_DQ<24>";
128"M_D_DQ<25>";
129"M_D_DQ<28>";
130"M_D_DQ<29>";
131"M_D_MA<2>";
132"M_D_BA<0>";
133"M_D_BG<1>";
134"M_D_BG<0>";
135"M_D_MA<3>";
136"M_D_MA<1>";
137"M_D_MA<0>";
138"M_D_BA<1>";
139"M_D_C<2>";
140"M_D_CS_N<4>";
141"M_D_CLK_DP<3>";
142"M_D_CLK_DN<2>";
143"M_D_CS_N<5>";
144"M_D_CS_N<6>";
145"M_D_CS_N<7>";
146"M_D_CLK_DP<2>";
147"M_D_CLK_DN<3>";
148"M_D_CKE<2>";
149"M_D_ODT<3>";
150"M_D_ODT<2>";
151"M_D_ECC<7>";
152"M_D_CKE<3>";
153"M_D_ECC<5>";
154"M_D_ECC<6>";
155"M_DEF_RST_N";
156"M_D_PAR";
157"M_D_ECC<0>";
158"M_D_ECC<1>";
159"M_D_ECC<2>";
160"M_D_ECC<3>";
161"M_D_ECC<4>";
162"M_D_DQ<5>";
163"M_D_DQ<4>";
164"M_D_DQ<3>";
165"M_D_DQ<2>";
166"M_D_DQ<1>";
167"M_D_DQ<6>";
168"M_D_DQ<7>";
169"M_D_DQ<8>";
170"SMB_DDR_DEF_VPP_SCL";
171"SMB_DDR_DEF_VPP_SDA";
172"M_D_ACT_N";
173"M_D_ALERT_N";
174"TP_CH_D_DIMM_D1_RFU_0";
175"TP_CH_D_DIMM_D1_RFU_2";
176"FM_DIMM_EVENT_COD_N";
%"GND"
"1","(5950,750)","2","mstr_symbols","I1";
;
VOLTAGE"0"
BOM_COST"MEM"
CDS_LIB"mstr_symbols"
SIZE"1B"
BODY_TYPE"PLUMBING"
ROOM"DDR4_CH_B"
HDL_POWER"GND";
"A\NAC"13;
%"TAP"
"6","(4350,4350)","2","mstr_standard","I10";
;
CDS_LIB"mstr_standard"
BODY_TYPE"PLUMBING"
HDL_TAP"TRUE";
"B \NAC \NWC"12;
"S \NAC"
BN"13"30;
%"TAP"
"6","(1700,3050)","2","mstr_standard","I100";
;
CDS_LIB"mstr_standard"
BODY_TYPE"PLUMBING"
HDL_TAP"TRUE";
"B \NAC \NWC"1;
"S \NAC"
BN"29"130;
%"TAP"
"6","(1700,2850)","2","mstr_standard","I101";
;
CDS_LIB"mstr_standard"
BODY_TYPE"PLUMBING"
HDL_TAP"TRUE";
"B \NAC \NWC"1;
"S \NAC"
BN"25"128;
%"TAP"
"6","(1700,2800)","2","mstr_standard","I102";
;
CDS_LIB"mstr_standard"
BODY_TYPE"PLUMBING"
HDL_TAP"TRUE";
"B \NAC \NWC"1;
"S \NAC"
BN"24"127;
%"TAP"
"6","(1700,2900)","2","mstr_standard","I103";
;
CDS_LIB"mstr_standard"
BODY_TYPE"PLUMBING"
HDL_TAP"TRUE";
"B \NAC \NWC"1;
"S \NAC"
BN"26"113;
%"TAP"
"6","(1700,2950)","2","mstr_standard","I104";
;
CDS_LIB"mstr_standard"
BODY_TYPE"PLUMBING"
HDL_TAP"TRUE";
"B \NAC \NWC"1;
"S \NAC"
BN"27"114;
%"TAP"
"6","(1700,3000)","2","mstr_standard","I105";
;
CDS_LIB"mstr_standard"
BODY_TYPE"PLUMBING"
HDL_TAP"TRUE";
"B \NAC \NWC"1;
"S \NAC"
BN"28"129;
%"TAP"
"6","(1700,2650)","2","mstr_standard","I106";
;
CDS_LIB"mstr_standard"
BODY_TYPE"PLUMBING"
HDL_TAP"TRUE";
"B \NAC \NWC"1;
"S \NAC"
BN"21"124;
%"TAP"
"6","(1700,2600)","2","mstr_standard","I107";
;
CDS_LIB"mstr_standard"
BODY_TYPE"PLUMBING"
HDL_TAP"TRUE";
"B \NAC \NWC"1;
"S \NAC"
BN"20"123;
%"TAP"
"6","(1700,2550)","2","mstr_standard","I108";
;
CDS_LIB"mstr_standard"
BODY_TYPE"PLUMBING"
HDL_TAP"TRUE";
"B \NAC \NWC"1;
"S \NAC"
BN"19"122;
%"TAP"
"6","(1700,2700)","2","mstr_standard","I109";
;
CDS_LIB"mstr_standard"
BODY_TYPE"PLUMBING"
HDL_TAP"TRUE";
"B \NAC \NWC"1;
"S \NAC"
BN"22"125;
%"TAP"
"6","(4350,4450)","2","mstr_standard","I11";
;
CDS_LIB"mstr_standard"
BODY_TYPE"PLUMBING"
HDL_TAP"TRUE";
"B \NAC \NWC"12;
"S \NAC"
BN"14"29;
%"TAP"
"6","(1700,2750)","2","mstr_standard","I110";
;
CDS_LIB"mstr_standard"
BODY_TYPE"PLUMBING"
HDL_TAP"TRUE";
"B \NAC \NWC"1;
"S \NAC"
BN"23"126;
%"TAP"
"6","(1700,2300)","2","mstr_standard","I111";
;
CDS_LIB"mstr_standard"
BODY_TYPE"PLUMBING"
HDL_TAP"TRUE";
"B \NAC \NWC"1;
"S \NAC"
BN"14"120;
%"TAP"
"6","(1700,2350)","2","mstr_standard","I112";
;
CDS_LIB"mstr_standard"
BODY_TYPE"PLUMBING"
HDL_TAP"TRUE";
"B \NAC \NWC"1;
"S \NAC"
BN"15"112;
%"TAP"
"6","(1700,2400)","2","mstr_standard","I113";
;
CDS_LIB"mstr_standard"
BODY_TYPE"PLUMBING"
HDL_TAP"TRUE";
"B \NAC \NWC"1;
"S \NAC"
BN"16"121;
%"TAP"
"6","(1700,2500)","2","mstr_standard","I114";
;
CDS_LIB"mstr_standard"
BODY_TYPE"PLUMBING"
HDL_TAP"TRUE";
"B \NAC \NWC"1;
"S \NAC"
BN"18"23;
%"TAP"
"6","(1700,2450)","2","mstr_standard","I115";
;
CDS_LIB"mstr_standard"
BODY_TYPE"PLUMBING"
HDL_TAP"TRUE";
"B \NAC \NWC"1;
"S \NAC"
BN"17"22;
%"TAP"
"6","(1700,2100)","2","mstr_standard","I116";
;
CDS_LIB"mstr_standard"
BODY_TYPE"PLUMBING"
HDL_TAP"TRUE";
"B \NAC \NWC"1;
"S \NAC"
BN"10"116;
%"TAP"
"6","(1700,2050)","2","mstr_standard","I117";
;
CDS_LIB"mstr_standard"
BODY_TYPE"PLUMBING"
HDL_TAP"TRUE";
"B \NAC \NWC"1;
"S \NAC"
BN"9"115;
%"TAP"
"6","(1700,2150)","2","mstr_standard","I118";
;
CDS_LIB"mstr_standard"
BODY_TYPE"PLUMBING"
HDL_TAP"TRUE";
"B \NAC \NWC"1;
"S \NAC"
BN"11"117;
%"TAP"
"6","(1700,2200)","2","mstr_standard","I119";
;
CDS_LIB"mstr_standard"
BODY_TYPE"PLUMBING"
HDL_TAP"TRUE";
"B \NAC \NWC"1;
"S \NAC"
BN"12"118;
%"TAP"
"6","(4350,4250)","2","mstr_standard","I12";
;
CDS_LIB"mstr_standard"
BODY_TYPE"PLUMBING"
HDL_TAP"TRUE";
"B \NAC \NWC"12;
"S \NAC"
BN"12"54;
%"TAP"
"6","(1700,2250)","2","mstr_standard","I120";
;
CDS_LIB"mstr_standard"
BODY_TYPE"PLUMBING"
HDL_TAP"TRUE";
"B \NAC \NWC"1;
"S \NAC"
BN"13"119;
%"TAP"
"6","(200,4050)","0","mstr_standard","I121";
;
CDS_LIB"mstr_standard"
BODY_TYPE"PLUMBING"
HDL_TAP"TRUE";
"B \NAC \NWC"9;
"S \NAC"
BN"3"135;
%"TAP"
"6","(200,3900)","0","mstr_standard","I122";
;
CDS_LIB"mstr_standard"
BODY_TYPE"PLUMBING"
HDL_TAP"TRUE";
"B \NAC \NWC"9;
"S \NAC"
BN"0"137;
%"TAP"
"6","(200,3950)","0","mstr_standard","I123";
;
CDS_LIB"mstr_standard"
BODY_TYPE"PLUMBING"
HDL_TAP"TRUE";
"B \NAC \NWC"9;
"S \NAC"
BN"1"136;
%"TAP"
"6","(200,4000)","0","mstr_standard","I124";
;
CDS_LIB"mstr_standard"
BODY_TYPE"PLUMBING"
HDL_TAP"TRUE";
"B \NAC \NWC"9;
"S \NAC"
BN"2"131;
%"TAP"
"6","(200,3800)","0","mstr_standard","I125";
;
CDS_LIB"mstr_standard"
BODY_TYPE"PLUMBING"
HDL_TAP"TRUE";
"B \NAC \NWC"8;
"S \NAC"
BN"1"138;
%"TAP"
"6","(200,3650)","0","mstr_standard","I126";
;
CDS_LIB"mstr_standard"
BODY_TYPE"PLUMBING"
HDL_TAP"TRUE";
"B \NAC \NWC"10;
"S \NAC"
BN"0"134;
%"TAP"
"6","(200,3750)","0","mstr_standard","I127";
;
CDS_LIB"mstr_standard"
BODY_TYPE"PLUMBING"
HDL_TAP"TRUE";
"B \NAC \NWC"8;
"S \NAC"
BN"0"132;
%"TAP"
"6","(200,3700)","0","mstr_standard","I128";
;
CDS_LIB"mstr_standard"
BODY_TYPE"PLUMBING"
HDL_TAP"TRUE";
"B \NAC \NWC"10;
"S \NAC"
BN"1"133;
%"TAP"
"6","(200,3550)","0","mstr_standard","I129";
;
CDS_LIB"mstr_standard"
BODY_TYPE"PLUMBING"
HDL_TAP"TRUE";
"B \NAC \NWC"6;
"S \NAC"
BN"3"141;
%"TAP"
"6","(4350,4150)","2","mstr_standard","I13";
;
CDS_LIB"mstr_standard"
BODY_TYPE"PLUMBING"
HDL_TAP"TRUE";
"B \NAC \NWC"12;
"S \NAC"
BN"11"45;
%"TAP"
"6","(200,3450)","0","mstr_standard","I130";
;
CDS_LIB"mstr_standard"
BODY_TYPE"PLUMBING"
HDL_TAP"TRUE";
"B \NAC \NWC"6;
"S \NAC"
BN"2"146;
%"TAP"
"6","(200,3250)","0","mstr_standard","I131";
;
CDS_LIB"mstr_standard"
BODY_TYPE"PLUMBING"
HDL_TAP"TRUE";
"B \NAC \NWC"7;
"S \NAC"
BN"7"145;
%"TAP"
"6","(200,3200)","0","mstr_standard","I132";
;
CDS_LIB"mstr_standard"
BODY_TYPE"PLUMBING"
HDL_TAP"TRUE";
"B \NAC \NWC"7;
"S \NAC"
BN"6"144;
%"TAP"
"6","(200,3150)","0","mstr_standard","I133";
;
CDS_LIB"mstr_standard"
BODY_TYPE"PLUMBING"
HDL_TAP"TRUE";
"B \NAC \NWC"7;
"S \NAC"
BN"5"143;
%"TAP"
"6","(200,3100)","0","mstr_standard","I134";
;
CDS_LIB"mstr_standard"
BODY_TYPE"PLUMBING"
HDL_TAP"TRUE";
"B \NAC \NWC"7;
"S \NAC"
BN"4"140;
%"TAP"
"6","(0,3500)","0","mstr_standard","I135";
;
CDS_LIB"mstr_standard"
BODY_TYPE"PLUMBING"
HDL_TAP"TRUE";
"B \NAC \NWC"5;
"S \NAC"
BN"3"147;
%"TAP"
"6","(0,3400)","0","mstr_standard","I136";
;
CDS_LIB"mstr_standard"
BODY_TYPE"PLUMBING"
HDL_TAP"TRUE";
"B \NAC \NWC"5;
"S \NAC"
BN"2"142;
%"TAP"
"6","(200,2800)","0","mstr_standard","I137";
;
CDS_LIB"mstr_standard"
BODY_TYPE"PLUMBING"
HDL_TAP"TRUE";
"B \NAC \NWC"4;
"S \NAC"
BN"2"150;
%"TAP"
"6","(200,2950)","0","mstr_standard","I138";
;
CDS_LIB"mstr_standard"
BODY_TYPE"PLUMBING"
HDL_TAP"TRUE";
"B \NAC \NWC"3;
"S \NAC"
BN"2"148;
%"TAP"
"6","(200,3000)","0","mstr_standard","I139";
;
CDS_LIB"mstr_standard"
BODY_TYPE"PLUMBING"
HDL_TAP"TRUE";
"B \NAC \NWC"3;
"S \NAC"
BN"3"152;
%"TAP"
"6","(4100,4500)","2","mstr_standard","I14";
;
CDS_LIB"mstr_standard"
BODY_TYPE"PLUMBING"
HDL_TAP"TRUE";
"B \NAC \NWC"11;
"S \NAC"
BN"14"60;
%"TAP"
"6","(200,2850)","0","mstr_standard","I140";
;
CDS_LIB"mstr_standard"
BODY_TYPE"PLUMBING"
HDL_TAP"TRUE";
"B \NAC \NWC"4;
"S \NAC"
BN"3"149;
%"TAP"
"6","(200,2650)","0","mstr_standard","I141";
;
CDS_LIB"mstr_standard"
BODY_TYPE"PLUMBING"
HDL_TAP"TRUE";
"B \NAC \NWC"2;
"S \NAC"
BN"6"154;
%"TAP"
"6","(200,2700)","0","mstr_standard","I142";
;
CDS_LIB"mstr_standard"
BODY_TYPE"PLUMBING"
HDL_TAP"TRUE";
"B \NAC \NWC"2;
"S \NAC"
BN"7"151;
%"TAP"
"6","(200,2600)","0","mstr_standard","I143";
;
CDS_LIB"mstr_standard"
BODY_TYPE"PLUMBING"
HDL_TAP"TRUE";
"B \NAC \NWC"2;
"S \NAC"
BN"5"153;
%"TAP"
"6","(200,2550)","0","mstr_standard","I144";
;
CDS_LIB"mstr_standard"
BODY_TYPE"PLUMBING"
HDL_TAP"TRUE";
"B \NAC \NWC"2;
"S \NAC"
BN"4"161;
%"TAP"
"6","(200,2350)","0","mstr_standard","I145";
;
CDS_LIB"mstr_standard"
BODY_TYPE"PLUMBING"
HDL_TAP"TRUE";
"B \NAC \NWC"2;
"S \NAC"
BN"0"157;
%"TAP"
"6","(200,2400)","0","mstr_standard","I146";
;
CDS_LIB"mstr_standard"
BODY_TYPE"PLUMBING"
HDL_TAP"TRUE";
"B \NAC \NWC"2;
"S \NAC"
BN"1"158;
%"TAP"
"6","(200,2450)","0","mstr_standard","I147";
;
CDS_LIB"mstr_standard"
BODY_TYPE"PLUMBING"
HDL_TAP"TRUE";
"B \NAC \NWC"2;
"S \NAC"
BN"2"159;
%"TAP"
"6","(200,2500)","0","mstr_standard","I148";
;
CDS_LIB"mstr_standard"
BODY_TYPE"PLUMBING"
HDL_TAP"TRUE";
"B \NAC \NWC"2;
"S \NAC"
BN"3"160;
%"TAP"
"6","(1700,1850)","2","mstr_standard","I149";
;
CDS_LIB"mstr_standard"
BODY_TYPE"PLUMBING"
HDL_TAP"TRUE";
"B \NAC \NWC"1;
"S \NAC"
BN"5"162;
%"TAP"
"6","(4100,4400)","2","mstr_standard","I15";
;
CDS_LIB"mstr_standard"
BODY_TYPE"PLUMBING"
HDL_TAP"TRUE";
"B \NAC \NWC"11;
"S \NAC"
BN"13"61;
%"TAP"
"6","(1700,1800)","2","mstr_standard","I150";
;
CDS_LIB"mstr_standard"
BODY_TYPE"PLUMBING"
HDL_TAP"TRUE";
"B \NAC \NWC"1;
"S \NAC"
BN"4"163;
%"TAP"
"6","(1700,1950)","2","mstr_standard","I151";
;
CDS_LIB"mstr_standard"
BODY_TYPE"PLUMBING"
HDL_TAP"TRUE";
"B \NAC \NWC"1;
"S \NAC"
BN"7"168;
%"TAP"
"6","(1700,2000)","2","mstr_standard","I152";
;
CDS_LIB"mstr_standard"
BODY_TYPE"PLUMBING"
HDL_TAP"TRUE";
"B \NAC \NWC"1;
"S \NAC"
BN"8"169;
%"TAP"
"6","(1700,1900)","2","mstr_standard","I153";
;
CDS_LIB"mstr_standard"
BODY_TYPE"PLUMBING"
HDL_TAP"TRUE";
"B \NAC \NWC"1;
"S \NAC"
BN"6"167;
%"TAP"
"6","(1700,1600)","2","mstr_standard","I154";
;
CDS_LIB"mstr_standard"
BODY_TYPE"PLUMBING"
HDL_TAP"TRUE";
"B \NAC \NWC"1;
"S \NAC"
BN"0"34;
%"TAP"
"6","(1700,1700)","2","mstr_standard","I155";
;
CDS_LIB"mstr_standard"
BODY_TYPE"PLUMBING"
HDL_TAP"TRUE";
"B \NAC \NWC"1;
"S \NAC"
BN"2"165;
%"TAP"
"6","(1700,1650)","2","mstr_standard","I156";
;
CDS_LIB"mstr_standard"
BODY_TYPE"PLUMBING"
HDL_TAP"TRUE";
"B \NAC \NWC"1;
"S \NAC"
BN"1"166;
%"TAP"
"6","(1700,1750)","2","mstr_standard","I157";
;
CDS_LIB"mstr_standard"
BODY_TYPE"PLUMBING"
HDL_TAP"TRUE";
"B \NAC \NWC"1;
"S \NAC"
BN"3"164;
%"SCONN288_H44441003"
"1","(950,3100)","0","mstr_sconn","I158";
;
CDS_SEC"1"
PART_NUMBER"H44441-003"
MATERIAL"SCONN"
LOCATION"J6M1"
BOM_SS"NOPOP"
PACK_TYPE"PIP"
BOM_COST"MEM"
CDS_LIB"mstr_sconn"
SEC_TYPE"PIP"
SEC"1"
CDS_LOCATION"J6M1"
ROOM"DDR4_CH_D";
"DQ<63>"
$PN"280"73;
"BA<1>"
$PN"224"138;
"CK1N"
$PN"219"147;
"CK0P"
$PN"74"146;
"S3_N_C<1>"
$PN"237"145;
"S2_N_C<0>"
$PN"93"144;
"S1_N"
$PN"89"143;
"DQ<29>"
$PN"181"130;
"DQ<28>"
$PN"36"129;
"C<2>"
$PN"235"139;
"A0"
$PN"79"137;
"A1"
$PN"72"136;
"A12"
$PN"65"86;
"A13"
$PN"232"85;
"A17"
$PN"234"76;
"A3"
$PN"71"135;
"A4"
$PN"214"84;
"A5"
$PN"213"83;
"A6"
$PN"69"82;
"A7"
$PN"211"81;
"A8"
$PN"68"80;
"A9"
$PN"66"79;
"CB<6>"
$PN"54"154;
"CB<5>"
$PN"192"153;
"CB<4>"
$PN"47"161;
"CB<3>"
$PN"201"160;
"CB<2>"
$PN"56"159;
"CB<1>"
$PN"194"158;
"CB<0>"
$PN"49"157;
"CK0N"
$PN"75"142;
"CKE<1>"
$PN"203"152;
"DQ<62>"
$PN"135"72;
"DQ<61>"
$PN"273"71;
"DQ<60>"
$PN"128"70;
"DQ<59>"
$PN"282"28;
"DQ<56>"
$PN"130"69;
"DQ<55>"
$PN"269"68;
"DQ<46>"
$PN"113"111;
"DQ<45>"
$PN"251"110;
"DQ<44>"
$PN"106"109;
"DQ<43>"
$PN"260"108;
"DQ<42>"
$PN"115"107;
"DQ<41>"
$PN"253"106;
"DQ<40>"
$PN"108"105;
"DQ<39>"
$PN"247"38;
"DQ<37>"
$PN"240"104;
"DQ<34>"
$PN"104"103;
"DQ<33>"
$PN"242"102;
"DQ<32>"
$PN"97"101;
"DQ<31>"
$PN"188"100;
"DQ<30>"
$PN"43"99;
"DQ<25>"
$PN"183"128;
"DQ<24>"
$PN"38"127;
"DQ<23>"
$PN"177"126;
"DQ<22>"
$PN"32"125;
"DQ<21>"
$PN"170"124;
"DQ<20>"
$PN"25"123;
"DQ<19>"
$PN"179"122;
"DQ<18>"
$PN"34"23;
"DQ<16>"
$PN"27"121;
"DQ<14>"
$PN"21"120;
"DQ<13>"
$PN"159"119;
"DQ<12>"
$PN"14"118;
"DQ<11>"
$PN"168"117;
"DQ<10>"
$PN"23"116;
"DQ<9>"
$PN"161"115;
"DQ<8>"
$PN"16"169;
"DQ<7>"
$PN"155"168;
"DQ<6>"
$PN"10"167;
"EVENT_N"
$PN"78"176;
"PAR"
$PN"222"156;
"RESET_N"
$PN"58"155;
"RFU<2>"
$PN"144"175;
"SCL"
$PN"141"170;
"SDA"
$PN"285"171;
"VREFCA"
$PN"146"37;
"CK1P"
$PN"218"141;
"BG<0>"
$PN"63"134;
"BG<1>"
$PN"207"133;
"BA<0>"
$PN"81"132;
"SA<0>"
$PN"139"14;
"VDDSPD"
$PN"284"14;
"SA<2>"
$PN"238"16;
"SA<1>"
$PN"140"16;
"DQ<1>"
$PN"150"166;
"DQ<0>"
$PN"5"34;
"ACT_N"
$PN"62"172;
"ALERT_N"
$PN"208"173;
"A2"
$PN"216"131;
"DQ<35>"
$PN"249"98;
"DQ<36>"
$PN"95"97;
"DQ<38>"
$PN"102"96;
"A10"
$PN"225"78;
"A11"
$PN"210"77;
"A14_WE_N"
$PN"228"35;
"A15_CAS_N"
$PN"86"75;
"A16_RAS_N"
$PN"82"74;
"CB<7>"
$PN"199"151;
"ODT<0>"
$PN"87"150;
"ODT<1>"
$PN"91"149;
"CKE<0>"
$PN"60"148;
"S0_N"
$PN"84"140;
"DQ<27>"
$PN"190"114;
"DQ<26>"
$PN"45"113;
"DQ<15>"
$PN"166"112;
"DQ<17>"
$PN"172"22;
"RFU<0>"
$PN"205"174;
"RFU<1>"
$PN"227"33;
"SAVE_N_NC"
$PN"230"36;
"DQ<57>"
$PN"275"43;
"DQ<58>"
$PN"137"27;
"DQ<54>"
$PN"124"67;
"DQ<53>"
$PN"262"31;
"DQ<52>"
$PN"117"44;
"DQ<51>"
$PN"271"66;
"DQ<50>"
$PN"126"65;
"DQ<49>"
$PN"264"32;
"DQ<48>"
$PN"119"95;
"DQ<47>"
$PN"258"94;
"DQ<2>"
$PN"12"165;
"DQ<3>"
$PN"157"164;
"DQ<4>"
$PN"3"163;
"DQ<5>"
$PN"148"162;
%"TAP"
"6","(4100,4300)","2","mstr_standard","I16";
;
CDS_LIB"mstr_standard"
BODY_TYPE"PLUMBING"
HDL_TAP"TRUE";
"B \NAC \NWC"11;
"S \NAC"
BN"12"62;
%"TAP"
"6","(4100,4200)","2","mstr_standard","I17";
;
CDS_LIB"mstr_standard"
BODY_TYPE"PLUMBING"
HDL_TAP"TRUE";
"B \NAC \NWC"11;
"S \NAC"
BN"11"63;
%"PVPP_DEF"
"1","(-1650,2100)","0","mstr_symbols","I172";
;
VOLTAGE"2.5V"
BOM_COST"MEM"
CDS_LIB"mstr_symbols"
BODY_TYPE"PLUMBING"
ROOM"DDR4_CH_B"
HDL_POWER"PVPP_DEF";
"G\NAC"14;
%"CAP_A"
"1","(-1200,1400)","2","dev_discrete","I177";
;
CDS_SEC"1"
LOCATION"C6M1"
VALUE"0.01UF"
VOLTAGE"25V"
PART_NUMBER"A36096-045"
MATERIAL"X7R"
TOLERANCE"10%"
PACK_TYPE"0402V"
CDS_LOCATION"C6M1"
BOM_COST"MEM"
CDS_LIB"dev_discrete"
ROOM"DDR4_CH_B"
SEC"1"
SEC_TYPE"0402V";
"B"
$PN"2"15;
"A"
$PN"1"37;
%"GND"
"1","(-1200,1150)","0","mstr_symbols","I178";
;
VOLTAGE"0"
CDS_LIB"mstr_symbols"
SIZE"1B"
BOM_COST"MEM"
BODY_TYPE"PLUMBING"
ROOM"DDR4_CH_B"
HDL_POWER"GND";
"A\NAC"15;
%"TAP"
"6","(4100,4100)","2","mstr_standard","I18";
;
CDS_LIB"mstr_standard"
BODY_TYPE"PLUMBING"
HDL_TAP"TRUE";
"B \NAC \NWC"11;
"S \NAC"
BN"10"64;
%"GND"
"1","(-1350,1775)","0","mstr_symbols","I180";
;
VOLTAGE"0"
BOM_COST"MEM"
SIZE"1B"
CDS_LIB"mstr_symbols"
BODY_TYPE"PLUMBING"
ROOM"DDR4_CH_B"
HDL_POWER"GND";
"A\NAC"16;
%"P12V_NVDIMM_DEF"
"1","(4100,2625)","0","mstr_symbols","I181";
;
VOLTAGE"12.0"
CDS_LIB"mstr_symbols"
BODY_TYPE"PLUMBING"
HDL_POWER"P12V_NVDIMM_DEF";
"G\NAC"17;
%"TAP"
"6","(4350,3950)","2","mstr_standard","I20";
;
CDS_LIB"mstr_standard"
BODY_TYPE"PLUMBING"
HDL_TAP"TRUE";
"B \NAC \NWC"12;
"S \NAC"
BN"9"46;
%"TAP"
"6","(4350,4050)","2","mstr_standard","I21";
;
CDS_LIB"mstr_standard"
BODY_TYPE"PLUMBING"
HDL_TAP"TRUE";
"B \NAC \NWC"12;
"S \NAC"
BN"10"55;
%"TAP"
"6","(4350,3850)","2","mstr_standard","I22";
;
CDS_LIB"mstr_standard"
BODY_TYPE"PLUMBING"
HDL_TAP"TRUE";
"B \NAC \NWC"12;
"S \NAC"
BN"8"39;
%"TAP"
"6","(4350,3750)","2","mstr_standard","I23";
;
CDS_LIB"mstr_standard"
BODY_TYPE"PLUMBING"
HDL_TAP"TRUE";
"B \NAC \NWC"12;
"S \NAC"
BN"7"47;
%"TAP"
"6","(4350,3650)","2","mstr_standard","I24";
;
CDS_LIB"mstr_standard"
BODY_TYPE"PLUMBING"
HDL_TAP"TRUE";
"B \NAC \NWC"12;
"S \NAC"
BN"6"48;
%"TAP"
"6","(4100,4000)","2","mstr_standard","I25";
;
CDS_LIB"mstr_standard"
BODY_TYPE"PLUMBING"
HDL_TAP"TRUE";
"B \NAC \NWC"11;
"S \NAC"
BN"9"87;
%"TAP"
"6","(4100,3900)","2","mstr_standard","I26";
;
CDS_LIB"mstr_standard"
BODY_TYPE"PLUMBING"
HDL_TAP"TRUE";
"B \NAC \NWC"11;
"S \NAC"
BN"8"88;
%"TAP"
"6","(4100,3700)","2","mstr_standard","I27";
;
CDS_LIB"mstr_standard"
BODY_TYPE"PLUMBING"
HDL_TAP"TRUE";
"B \NAC \NWC"11;
"S \NAC"
BN"6"90;
%"TAP"
"6","(4100,3800)","2","mstr_standard","I28";
;
CDS_LIB"mstr_standard"
BODY_TYPE"PLUMBING"
HDL_TAP"TRUE";
"B \NAC \NWC"11;
"S \NAC"
BN"7"89;
%"TAP"
"6","(4100,3600)","2","mstr_standard","I29";
;
CDS_LIB"mstr_standard"
BODY_TYPE"PLUMBING"
HDL_TAP"TRUE";
"B \NAC \NWC"11;
"S \NAC"
BN"5"91;
%"TAP"
"6","(4350,3550)","2","mstr_standard","I30";
;
CDS_LIB"mstr_standard"
BODY_TYPE"PLUMBING"
HDL_TAP"TRUE";
"B \NAC \NWC"12;
"S \NAC"
BN"5"25;
%"TAP"
"6","(4350,3450)","2","mstr_standard","I31";
;
CDS_LIB"mstr_standard"
BODY_TYPE"PLUMBING"
HDL_TAP"TRUE";
"B \NAC \NWC"12;
"S \NAC"
BN"4"49;
%"TAP"
"6","(4350,3350)","2","mstr_standard","I32";
;
CDS_LIB"mstr_standard"
BODY_TYPE"PLUMBING"
HDL_TAP"TRUE";
"B \NAC \NWC"12;
"S \NAC"
BN"3"50;
%"TAP"
"6","(4350,3250)","2","mstr_standard","I33";
;
CDS_LIB"mstr_standard"
BODY_TYPE"PLUMBING"
HDL_TAP"TRUE";
"B \NAC \NWC"12;
"S \NAC"
BN"2"41;
%"TAP"
"6","(4350,3050)","2","mstr_standard","I34";
;
CDS_LIB"mstr_standard"
BODY_TYPE"PLUMBING"
HDL_TAP"TRUE";
"B \NAC \NWC"12;
"S \NAC"
BN"0"56;
%"TAP"
"6","(4350,3150)","2","mstr_standard","I35";
;
CDS_LIB"mstr_standard"
BODY_TYPE"PLUMBING"
HDL_TAP"TRUE";
"B \NAC \NWC"12;
"S \NAC"
BN"1"40;
%"TAP"
"6","(4100,3500)","2","mstr_standard","I36";
;
CDS_LIB"mstr_standard"
BODY_TYPE"PLUMBING"
HDL_TAP"TRUE";
"B \NAC \NWC"11;
"S \NAC"
BN"4"26;
%"TAP"
"6","(4100,3400)","2","mstr_standard","I37";
;
CDS_LIB"mstr_standard"
BODY_TYPE"PLUMBING"
HDL_TAP"TRUE";
"B \NAC \NWC"11;
"S \NAC"
BN"3"92;
%"TAP"
"6","(4100,3300)","2","mstr_standard","I38";
;
CDS_LIB"mstr_standard"
BODY_TYPE"PLUMBING"
HDL_TAP"TRUE";
"B \NAC \NWC"11;
"S \NAC"
BN"2"42;
%"TAP"
"6","(4100,3200)","2","mstr_standard","I39";
;
CDS_LIB"mstr_standard"
BODY_TYPE"PLUMBING"
HDL_TAP"TRUE";
"B \NAC \NWC"11;
"S \NAC"
BN"1"93;
%"TAP"
"6","(4350,4750)","2","mstr_standard","I4";
;
CDS_LIB"mstr_standard"
BODY_TYPE"PLUMBING"
HDL_TAP"TRUE";
"B \NAC \NWC"12;
"S \NAC"
BN"17"51;
%"TAP"
"6","(4100,3100)","2","mstr_standard","I40";
;
CDS_LIB"mstr_standard"
BODY_TYPE"PLUMBING"
HDL_TAP"TRUE";
"B \NAC \NWC"11;
"S \NAC"
BN"0"24;
%"SCONN288_H44441003"
"3","(5250,2050)","0","mstr_sconn","I44";
;
CDS_SEC"3"
LOCATION"J6M1"
PART_NUMBER"H44441-003"
MATERIAL"SCONN"
BOM_SS"NOPOP"
PACK_TYPE"PIP"
BOM_COST"MEM"
CDS_LIB"mstr_sconn"
SEC_TYPE"PIP"
SEC"3"
CDS_LOCATION"J6M1"
ROOM"DDR4_CH_D";
"VSS<46>"
$PN"147"13;
"VSS<45>"
$PN"149"13;
"VSS<87>"
$PN"15"18;
"VSS<86>"
$PN"17"18;
"VSS<85>"
$PN"20"18;
"VSS<84>"
$PN"22"18;
"VSS<83>"
$PN"24"18;
"VSS<82>"
$PN"26"18;
"VSS<81>"
$PN"28"18;
"VSS<80>"
$PN"31"18;
"VSS<79>"
$PN"33"18;
"VSS<78>"
$PN"35"18;
"VSS<77>"
$PN"37"18;
"VSS<76>"
$PN"39"18;
"VSS<75>"
$PN"42"18;
"VSS<74>"
$PN"44"18;
"VSS<73>"
$PN"46"18;
"VSS<72>"
$PN"48"18;
"VSS<71>"
$PN"50"18;
"VSS<70>"
$PN"53"18;
"VSS<69>"
$PN"55"18;
"VSS<68>"
$PN"57"18;
"VSS<67>"
$PN"94"18;
"VSS<66>"
$PN"96"18;
"VSS<65>"
$PN"98"18;
"VSS<64>"
$PN"101"18;
"VSS<63>"
$PN"103"18;
"VSS<62>"
$PN"105"18;
"VSS<61>"
$PN"107"18;
"VSS<60>"
$PN"109"18;
"VSS<59>"
$PN"112"18;
"VSS<58>"
$PN"114"18;
"VSS<57>"
$PN"116"18;
"VSS<56>"
$PN"118"18;
"VSS<55>"
$PN"120"18;
"VSS<54>"
$PN"123"18;
"VSS<53>"
$PN"125"18;
"VSS<52>"
$PN"127"18;
"VSS<51>"
$PN"129"18;
"VSS<50>"
$PN"131"18;
"VSS<49>"
$PN"134"18;
"VSS<48>"
$PN"136"18;
"VSS<47>"
$PN"138"18;
"VSS<44>"
$PN"151"13;
"VSS<43>"
$PN"154"13;
"VSS<42>"
$PN"156"13;
"VSS<41>"
$PN"158"13;
"VSS<40>"
$PN"160"13;
"VSS<39>"
$PN"162"13;
"VSS<38>"
$PN"165"13;
"VSS<37>"
$PN"167"13;
"VSS<36>"
$PN"169"13;
"VSS<35>"
$PN"171"13;
"VSS<34>"
$PN"173"13;
"VSS<33>"
$PN"176"13;
"VSS<32>"
$PN"178"13;
"VSS<31>"
$PN"180"13;
"VSS<30>"
$PN"182"13;
"VSS<29>"
$PN"184"13;
"VSS<28>"
$PN"187"13;
"VSS<27>"
$PN"189"13;
"VSS<26>"
$PN"191"13;
"VSS<25>"
$PN"193"13;
"VSS<24>"
$PN"195"13;
"VSS<23>"
$PN"198"13;
"VSS<22>"
$PN"200"13;
"VSS<21>"
$PN"202"13;
"VSS<20>"
$PN"239"13;
"VSS<19>"
$PN"241"13;
"VSS<18>"
$PN"243"13;
"VSS<17>"
$PN"246"13;
"VSS<16>"
$PN"248"13;
"VSS<15>"
$PN"250"13;
"VSS<14>"
$PN"252"13;
"VSS<13>"
$PN"254"13;
"VSS<12>"
$PN"257"13;
"VSS<11>"
$PN"259"13;
"VSS<10>"
$PN"261"13;
"VSS<9>"
$PN"263"13;
"VSS<8>"
$PN"265"13;
"VSS<7>"
$PN"268"13;
"VSS<6>"
$PN"270"13;
"VSS<5>"
$PN"272"13;
"VSS<4>"
$PN"274"13;
"VSS<3>"
$PN"276"13;
"VSS<2>"
$PN"279"13;
"VSS<1>"
$PN"281"13;
"VSS<0>"
$PN"283"13;
"VSS<88>"
$PN"13"18;
"VSS<89>"
$PN"11"18;
"VSS<90>"
$PN"9"18;
"VSS<91>"
$PN"6"18;
"VSS<92>"
$PN"4"18;
"VSS<93>"
$PN"2"18;
%"GND"
"1","(4550,750)","2","mstr_symbols","I45";
;
VOLTAGE"0"
BOM_COST"MEM"
CDS_LIB"mstr_symbols"
SIZE"1B"
BODY_TYPE"PLUMBING"
ROOM"DDR4_CH_B"
HDL_POWER"GND";
"A\NAC"18;
%"SCONN288_H44441003"
"2","(3400,3950)","0","mstr_sconn","I46";
;
CDS_SEC"2"
LOCATION"J6M1"
MATERIAL"SCONN"
BOM_SS"NOPOP"
PART_NUMBER"H44441-003"
PACK_TYPE"PIP"
BOM_COST"MEM"
CDS_LIB"mstr_sconn"
SEC_TYPE"PIP"
SEC"2"
CDS_LOCATION"J6M1"
ROOM"DDR4_CH_D";
"DQS0N"
$PN"152"56;
"DQS0P"
$PN"153"24;
"DQS10N"
$PN"19"55;
"DQS10P"
$PN"18"64;
"DQS11N"
$PN"30"45;
"DQS11P"
$PN"29"63;
"DQS12N"
$PN"41"54;
"DQS12P"
$PN"40"62;
"DQS13N"
$PN"100"30;
"DQS13P"
$PN"99"61;
"DQS14N"
$PN"111"29;
"DQS14P"
$PN"110"60;
"DQS15N"
$PN"122"53;
"DQS15P"
$PN"121"59;
"DQS16N"
$PN"133"52;
"DQS16P"
$PN"132"58;
"DQS17N"
$PN"52"51;
"DQS17P"
$PN"51"57;
"DQS1N"
$PN"163"40;
"DQS1P"
$PN"164"93;
"DQS2N"
$PN"174"41;
"DQS2P"
$PN"175"42;
"DQS3N"
$PN"185"50;
"DQS3P"
$PN"186"92;
"DQS4N"
$PN"244"49;
"DQS4P"
$PN"245"26;
"DQS5N"
$PN"255"25;
"DQS5P"
$PN"256"91;
"DQS6N"
$PN"266"48;
"DQS6P"
$PN"267"90;
"DQS7N"
$PN"277"47;
"DQS7P"
$PN"278"89;
"DQS8N"
$PN"196"39;
"DQS8P"
$PN"197"88;
"DQS9N"
$PN"8"46;
"DQS9P"
$PN"7"87;
%"PVPP_DEF"
"1","(2700,2550)","0","mstr_symbols","I47";
;
VOLTAGE"2.5V"
BOM_COST"MEM"
CDS_LIB"mstr_symbols"
BODY_TYPE"PLUMBING"
ROOM"DDR4_CH_B"
HDL_POWER"PVPP_DEF";
"G\NAC"19;
%"PVTT_DEF"
"1","(2550,2250)","0","mstr_symbols","I48";
;
VOLTAGE"0.6V"
BOM_COST"MEM"
CDS_LIB"mstr_symbols"
BODY_TYPE"PLUMBING"
ROOM"DDR4_CH_B"
HDL_POWER"PVTT_DEF";
"G\NAC"20;
%"PVDDQ_DEF"
"1","(2300,2100)","0","mstr_symbols","I49";
;
VOLTAGE"1.2V"
BOM_COST"MEM"
CDS_LIB"mstr_symbols"
BODY_TYPE"PLUMBING"
ROOM"DDR4_CH_B"
HDL_POWER"PVDDQ_DEF";
"G\NAC"21;
%"TAP"
"6","(4350,4650)","2","mstr_standard","I5";
;
CDS_LIB"mstr_standard"
BODY_TYPE"PLUMBING"
HDL_TAP"TRUE";
"B \NAC \NWC"12;
"S \NAC"
BN"16"52;
%"SCONN288_H44441003"
"4","(3400,1550)","0","mstr_sconn","I50";
;
CDS_SEC"4"
LOCATION"J6M1"
PART_NUMBER"H44441-003"
MATERIAL"SCONN"
BOM_SS"NOPOP"
PACK_TYPE"PIP"
BOM_COST"MEM"
CDS_LIB"mstr_sconn"
SEC_TYPE"PIP"
SEC"4"
CDS_LOCATION"J6M1"
ROOM"DDR4_CH_D";
"VDD<0>"
$PN"236"21;
"VDD<6>"
$PN"220"21;
"VDD<10>"
$PN"209"21;
"VDD<13>"
$PN"92"21;
"VDD<16>"
$PN"85"21;
"VDD<19>"
$PN"76"21;
"VDD<23>"
$PN"64"21;
"VDD<25>"
$PN"59"21;
"VTT<0>"
$PN"221"20;
"12V<1>"
$PN"1"17;
"12V<0>"
$PN"145"17;
"VDD<24>"
$PN"61"21;
"VDD<22>"
$PN"67"21;
"VDD<21>"
$PN"70"21;
"VDD<20>"
$PN"73"21;
"VDD<18>"
$PN"80"21;
"VDD<17>"
$PN"83"21;
"VDD<15>"
$PN"88"21;
"VDD<14>"
$PN"90"21;
"VDD<12>"
$PN"204"21;
"VDD<11>"
$PN"206"21;
"VDD<9>"
$PN"212"21;
"VDD<8>"
$PN"215"21;
"VDD<7>"
$PN"217"21;
"VDD<5>"
$PN"223"21;
"VDD<4>"
$PN"226"21;
"VDD<3>"
$PN"229"21;
"VDD<2>"
$PN"231"21;
"VDD<1>"
$PN"233"21;
"VPP<4>"
$PN"142"19;
"VPP<3>"
$PN"143"19;
"VPP<2>"
$PN"288"19;
"VPP<1>"
$PN"286"19;
"VPP<0>"
$PN"287"19;
"VTT<1>"
$PN"77"20;
%"TAP"
"6","(1700,4700)","2","mstr_standard","I51";
;
CDS_LIB"mstr_standard"
BODY_TYPE"PLUMBING"
HDL_TAP"TRUE";
"B \NAC \NWC"1;
"S \NAC"
BN"62"72;
%"TAP"
"6","(1700,4600)","2","mstr_standard","I52";
;
CDS_LIB"mstr_standard"
BODY_TYPE"PLUMBING"
HDL_TAP"TRUE";
"B \NAC \NWC"1;
"S \NAC"
BN"60"70;
%"TAP"
"6","(1700,4650)","2","mstr_standard","I53";
;
CDS_LIB"mstr_standard"
BODY_TYPE"PLUMBING"
HDL_TAP"TRUE";
"B \NAC \NWC"1;
"S \NAC"
BN"61"71;
%"TAP"
"6","(1700,4750)","2","mstr_standard","I54";
;
CDS_LIB"mstr_standard"
BODY_TYPE"PLUMBING"
HDL_TAP"TRUE";
"B \NAC \NWC"1;
"S \NAC"
BN"63"73;
%"TAP"
"6","(1700,4350)","2","mstr_standard","I55";
;
CDS_LIB"mstr_standard"
BODY_TYPE"PLUMBING"
HDL_TAP"TRUE";
"B \NAC \NWC"1;
"S \NAC"
BN"55"68;
%"TAP"
"6","(1700,4400)","2","mstr_standard","I56";
;
CDS_LIB"mstr_standard"
BODY_TYPE"PLUMBING"
HDL_TAP"TRUE";
"B \NAC \NWC"1;
"S \NAC"
BN"56"69;
%"TAP"
"6","(1700,4450)","2","mstr_standard","I57";
;
CDS_LIB"mstr_standard"
BODY_TYPE"PLUMBING"
HDL_TAP"TRUE";
"B \NAC \NWC"1;
"S \NAC"
BN"57"43;
%"TAP"
"6","(1700,4550)","2","mstr_standard","I58";
;
CDS_LIB"mstr_standard"
BODY_TYPE"PLUMBING"
HDL_TAP"TRUE";
"B \NAC \NWC"1;
"S \NAC"
BN"59"28;
%"TAP"
"6","(1700,4500)","2","mstr_standard","I59";
;
CDS_LIB"mstr_standard"
BODY_TYPE"PLUMBING"
HDL_TAP"TRUE";
"B \NAC \NWC"1;
"S \NAC"
BN"58"27;
%"TAP"
"6","(4100,4800)","2","mstr_standard","I6";
;
CDS_LIB"mstr_standard"
BODY_TYPE"PLUMBING"
HDL_TAP"TRUE";
"B \NAC \NWC"11;
"S \NAC"
BN"17"57;
%"TAP"
"6","(1700,4200)","2","mstr_standard","I60";
;
CDS_LIB"mstr_standard"
BODY_TYPE"PLUMBING"
HDL_TAP"TRUE";
"B \NAC \NWC"1;
"S \NAC"
BN"52"44;
%"TAP"
"6","(1700,4150)","2","mstr_standard","I61";
;
CDS_LIB"mstr_standard"
BODY_TYPE"PLUMBING"
HDL_TAP"TRUE";
"B \NAC \NWC"1;
"S \NAC"
BN"51"66;
%"TAP"
"6","(1700,4100)","2","mstr_standard","I62";
;
CDS_LIB"mstr_standard"
BODY_TYPE"PLUMBING"
HDL_TAP"TRUE";
"B \NAC \NWC"1;
"S \NAC"
BN"50"65;
%"TAP"
"6","(1700,4250)","2","mstr_standard","I63";
;
CDS_LIB"mstr_standard"
BODY_TYPE"PLUMBING"
HDL_TAP"TRUE";
"B \NAC \NWC"1;
"S \NAC"
BN"53"31;
%"TAP"
"6","(1700,4300)","2","mstr_standard","I64";
;
CDS_LIB"mstr_standard"
BODY_TYPE"PLUMBING"
HDL_TAP"TRUE";
"B \NAC \NWC"1;
"S \NAC"
BN"54"67;
%"TAP"
"6","(200,4700)","0","mstr_standard","I65";
;
CDS_LIB"mstr_standard"
BODY_TYPE"PLUMBING"
HDL_TAP"TRUE";
"B \NAC \NWC"9;
"S \NAC"
BN"16"74;
%"TAP"
"6","(200,4750)","0","mstr_standard","I66";
;
CDS_LIB"mstr_standard"
BODY_TYPE"PLUMBING"
HDL_TAP"TRUE";
"B \NAC \NWC"9;
"S \NAC"
BN"17"76;
%"TAP"
"6","(200,4650)","0","mstr_standard","I67";
;
CDS_LIB"mstr_standard"
BODY_TYPE"PLUMBING"
HDL_TAP"TRUE";
"B \NAC \NWC"9;
"S \NAC"
BN"15"75;
%"TAP"
"6","(200,4600)","0","mstr_standard","I68";
;
CDS_LIB"mstr_standard"
BODY_TYPE"PLUMBING"
HDL_TAP"TRUE";
"B \NAC \NWC"9;
"S \NAC"
BN"14"35;
%"TAP"
"6","(200,4550)","0","mstr_standard","I69";
;
CDS_LIB"mstr_standard"
BODY_TYPE"PLUMBING"
HDL_TAP"TRUE";
"B \NAC \NWC"9;
"S \NAC"
BN"13"85;
%"TAP"
"6","(4100,4600)","2","mstr_standard","I7";
;
CDS_LIB"mstr_standard"
BODY_TYPE"PLUMBING"
HDL_TAP"TRUE";
"B \NAC \NWC"11;
"S \NAC"
BN"15"59;
%"TAP"
"6","(200,4500)","0","mstr_standard","I70";
;
CDS_LIB"mstr_standard"
BODY_TYPE"PLUMBING"
HDL_TAP"TRUE";
"B \NAC \NWC"9;
"S \NAC"
BN"12"86;
%"TAP"
"6","(200,4450)","0","mstr_standard","I71";
;
CDS_LIB"mstr_standard"
BODY_TYPE"PLUMBING"
HDL_TAP"TRUE";
"B \NAC \NWC"9;
"S \NAC"
BN"11"77;
%"TAP"
"6","(200,4400)","0","mstr_standard","I72";
;
CDS_LIB"mstr_standard"
BODY_TYPE"PLUMBING"
HDL_TAP"TRUE";
"B \NAC \NWC"9;
"S \NAC"
BN"10"78;
%"TAP"
"6","(200,4350)","0","mstr_standard","I73";
;
CDS_LIB"mstr_standard"
BODY_TYPE"PLUMBING"
HDL_TAP"TRUE";
"B \NAC \NWC"9;
"S \NAC"
BN"9"79;
%"TAP"
"6","(200,4300)","0","mstr_standard","I74";
;
CDS_LIB"mstr_standard"
BODY_TYPE"PLUMBING"
HDL_TAP"TRUE";
"B \NAC \NWC"9;
"S \NAC"
BN"8"80;
%"TAP"
"6","(200,4250)","0","mstr_standard","I75";
;
CDS_LIB"mstr_standard"
BODY_TYPE"PLUMBING"
HDL_TAP"TRUE";
"B \NAC \NWC"9;
"S \NAC"
BN"7"81;
%"TAP"
"6","(200,4200)","0","mstr_standard","I76";
;
CDS_LIB"mstr_standard"
BODY_TYPE"PLUMBING"
HDL_TAP"TRUE";
"B \NAC \NWC"9;
"S \NAC"
BN"6"82;
%"TAP"
"6","(200,4150)","0","mstr_standard","I77";
;
CDS_LIB"mstr_standard"
BODY_TYPE"PLUMBING"
HDL_TAP"TRUE";
"B \NAC \NWC"9;
"S \NAC"
BN"5"83;
%"TAP"
"6","(200,4100)","0","mstr_standard","I78";
;
CDS_LIB"mstr_standard"
BODY_TYPE"PLUMBING"
HDL_TAP"TRUE";
"B \NAC \NWC"9;
"S \NAC"
BN"4"84;
%"TAP"
"6","(4100,4700)","2","mstr_standard","I8";
;
CDS_LIB"mstr_standard"
BODY_TYPE"PLUMBING"
HDL_TAP"TRUE";
"B \NAC \NWC"11;
"S \NAC"
BN"16"58;
%"TAP"
"6","(1700,3950)","2","mstr_standard","I80";
;
CDS_LIB"mstr_standard"
BODY_TYPE"PLUMBING"
HDL_TAP"TRUE";
"B \NAC \NWC"1;
"S \NAC"
BN"47"94;
%"TAP"
"6","(1700,3850)","2","mstr_standard","I81";
;
CDS_LIB"mstr_standard"
BODY_TYPE"PLUMBING"
HDL_TAP"TRUE";
"B \NAC \NWC"1;
"S \NAC"
BN"45"110;
%"TAP"
"6","(1700,4000)","2","mstr_standard","I82";
;
CDS_LIB"mstr_standard"
BODY_TYPE"PLUMBING"
HDL_TAP"TRUE";
"B \NAC \NWC"1;
"S \NAC"
BN"48"95;
%"TAP"
"6","(1700,4050)","2","mstr_standard","I83";
;
CDS_LIB"mstr_standard"
BODY_TYPE"PLUMBING"
HDL_TAP"TRUE";
"B \NAC \NWC"1;
"S \NAC"
BN"49"32;
%"TAP"
"6","(1700,3900)","2","mstr_standard","I84";
;
CDS_LIB"mstr_standard"
BODY_TYPE"PLUMBING"
HDL_TAP"TRUE";
"B \NAC \NWC"1;
"S \NAC"
BN"46"111;
%"TAP"
"6","(1700,3700)","2","mstr_standard","I85";
;
CDS_LIB"mstr_standard"
BODY_TYPE"PLUMBING"
HDL_TAP"TRUE";
"B \NAC \NWC"1;
"S \NAC"
BN"42"107;
%"TAP"
"6","(1700,3750)","2","mstr_standard","I86";
;
CDS_LIB"mstr_standard"
BODY_TYPE"PLUMBING"
HDL_TAP"TRUE";
"B \NAC \NWC"1;
"S \NAC"
BN"43"108;
%"TAP"
"6","(1700,3800)","2","mstr_standard","I87";
;
CDS_LIB"mstr_standard"
BODY_TYPE"PLUMBING"
HDL_TAP"TRUE";
"B \NAC \NWC"1;
"S \NAC"
BN"44"109;
%"TAP"
"6","(1700,3650)","2","mstr_standard","I88";
;
CDS_LIB"mstr_standard"
BODY_TYPE"PLUMBING"
HDL_TAP"TRUE";
"B \NAC \NWC"1;
"S \NAC"
BN"41"106;
%"TAP"
"6","(1700,3600)","2","mstr_standard","I89";
;
CDS_LIB"mstr_standard"
BODY_TYPE"PLUMBING"
HDL_TAP"TRUE";
"B \NAC \NWC"1;
"S \NAC"
BN"40"105;
%"TAP"
"6","(4350,4550)","2","mstr_standard","I9";
;
CDS_LIB"mstr_standard"
BODY_TYPE"PLUMBING"
HDL_TAP"TRUE";
"B \NAC \NWC"12;
"S \NAC"
BN"15"53;
%"TAP"
"6","(1700,3350)","2","mstr_standard","I90";
;
CDS_LIB"mstr_standard"
BODY_TYPE"PLUMBING"
HDL_TAP"TRUE";
"B \NAC \NWC"1;
"S \NAC"
BN"35"98;
%"TAP"
"6","(1700,3400)","2","mstr_standard","I91";
;
CDS_LIB"mstr_standard"
BODY_TYPE"PLUMBING"
HDL_TAP"TRUE";
"B \NAC \NWC"1;
"S \NAC"
BN"36"97;
%"TAP"
"6","(1700,3500)","2","mstr_standard","I92";
;
CDS_LIB"mstr_standard"
BODY_TYPE"PLUMBING"
HDL_TAP"TRUE";
"B \NAC \NWC"1;
"S \NAC"
BN"38"96;
%"TAP"
"6","(1700,3450)","2","mstr_standard","I93";
;
CDS_LIB"mstr_standard"
BODY_TYPE"PLUMBING"
HDL_TAP"TRUE";
"B \NAC \NWC"1;
"S \NAC"
BN"37"104;
%"TAP"
"6","(1700,3550)","2","mstr_standard","I94";
;
CDS_LIB"mstr_standard"
BODY_TYPE"PLUMBING"
HDL_TAP"TRUE";
"B \NAC \NWC"1;
"S \NAC"
BN"39"38;
%"TAP"
"6","(1700,3200)","2","mstr_standard","I95";
;
CDS_LIB"mstr_standard"
BODY_TYPE"PLUMBING"
HDL_TAP"TRUE";
"B \NAC \NWC"1;
"S \NAC"
BN"32"101;
%"TAP"
"6","(1700,3250)","2","mstr_standard","I96";
;
CDS_LIB"mstr_standard"
BODY_TYPE"PLUMBING"
HDL_TAP"TRUE";
"B \NAC \NWC"1;
"S \NAC"
BN"33"102;
%"TAP"
"6","(1700,3300)","2","mstr_standard","I97";
;
CDS_LIB"mstr_standard"
BODY_TYPE"PLUMBING"
HDL_TAP"TRUE";
"B \NAC \NWC"1;
"S \NAC"
BN"34"103;
%"TAP"
"6","(1700,3100)","2","mstr_standard","I98";
;
CDS_LIB"mstr_standard"
BODY_TYPE"PLUMBING"
HDL_TAP"TRUE";
"B \NAC \NWC"1;
"S \NAC"
BN"30"99;
%"TAP"
"6","(1700,3150)","2","mstr_standard","I99";
;
CDS_LIB"mstr_standard"
BODY_TYPE"PLUMBING"
HDL_TAP"TRUE";
"B \NAC \NWC"1;
"S \NAC"
BN"31"100;
END.
